# TIMECARD (Time Appliance Project (Time Card)) — schematic netlist excerpt (pin names and nets, part order shuffled) for the footprints in the layout excerpt that follows; sources: Cadence DE-HDL packaged netlist, KiCad conversion of R4006-B0001-02_R01.brd

TP9  TP_PIONT  pkg TP010CT020B030_PTH  page 24 : \1\ = UNNAMED_524_FT4232HLREELQFP64_4
L15  FERRITEBEAD  120OHM 25%  pkg SMC_0603R_H030  page 22 : \1\ = XP5R0V ; \2\ = XP5R0V_VCC_ANT

(kicad_pcb
	(version 20260206)
	(generator "pcbnew")
	(generator_version "10.0")
	(general
		(thickness 1.6)
		(legacy_teardrops no)
	)
	(paper "A4")
	(title_block
		(title "timecard-production-celestica-r4006 — R4006-B0001-02_R01.brd")
		(comment 1 "Time Appliance Project (Time Card) / footprints 375-376 of 1113")
	)
	(layers
		(0 "F.Cu" signal "TOP")
		(4 "In1.Cu" signal "L02_GND1")
		(6 "In2.Cu" signal "L03_SIG1")
		(8 "In3.Cu" signal "L04_GND2")
		(10 "In4.Cu" signal "L05_VCC1")
		(12 "In5.Cu" signal "L06_VCC2")
		(14 "In6.Cu" signal "L07_GND3")
		(16 "In7.Cu" signal "L08_SIG2")
		(18 "In8.Cu" signal "L09_GND4")
		(2 "B.Cu" signal "BOTTOM")
		(9 "F.Adhes" user "F.Adhesive")
		(11 "B.Adhes" user "B.Adhesive")
		(13 "F.Paste" user "Package Geometry/Pastemask Top")
		(15 "B.Paste" user "Package Geometry/Pastemask Bottom")
		(5 "F.SilkS" user "Ref Des/Silkscreen Top")
		(7 "B.SilkS" user "Ref Des/Silkscreen Bottom")
		(1 "F.Mask" user "Board Geometry/Soldermask Top")
		(3 "B.Mask" user "Board Geometry/Soldermask Bottom")
		(17 "Dwgs.User" user "User.Drawings")
		(19 "Cmts.User" user "User.Comments")
		(21 "Eco1.User" user "User.Eco1")
		(23 "Eco2.User" user "User.Eco2")
		(25 "Edge.Cuts" user "Board Geometry/Outline")
		(27 "Margin" user)
		(31 "F.CrtYd" user "Package Geometry/Place Bound Top")
		(29 "B.CrtYd" user "Package Geometry/Place Bound Bottom")
		(35 "F.Fab" user "Ref Des/Assembly Top")
		(33 "B.Fab" user "Ref Des/Assembly Bottom")
	)
	(footprint ""
		(layer "F.Cu")
		(at 130.048 -98.552 90)
		(property "Reference" "L15"
			(at 1.5875 0.67437 90)
			(unlocked yes)
			(layer "F.SilkS")
			(effects
				(font
					(size 0.7874 0.5842)
					(thickness 0.1524)
				)
				(justify left)
			)
		)
		(property "Value" "VAL*"
			(at -0.9398 3.70967 90)
			(unlocked yes)
			(layer "F.Fab")
			(hide yes)
			(effects
				(font
					(size 0.7874 0.5842)
					(thickness 0.1524)
				)
				(justify left)
			)
		)
		(property "Tolerance" "TOL*"
			(at -0.9906 5.00507 90)
			(unlocked yes)
			(layer "Cmts.User")
			(hide yes)
			(effects
				(font
					(size 0.7874 0.5842)
					(thickness 0.1524)
				)
				(justify left)
			)
		)
		(property "User Part Number" "PARTNUM*"
			(at -2.54 2.46507 90)
			(unlocked yes)
			(layer "Cmts.User")
			(hide yes)
			(effects
				(font
					(size 0.7874 0.5842)
					(thickness 0.1524)
				)
				(justify left)
			)
		)
		(property "Device Type" "FERRITEBEAD-G191-10100-01,120OA"
			(at -0.9906 1.22047 90)
			(unlocked yes)
			(layer "F.Fab")
			(hide yes)
			(effects
				(font
					(size 0.7874 0.5842)
					(thickness 0.1524)
				)
				(justify left)
			)
		)
		(duplicate_pad_numbers_are_jumpers no)
		(fp_line
			(start 1.3208 -0.7112)
			(end 1.3208 0.7112)
			(stroke
				(width 0.1)
				(type default)
			)
			(layer "F.SilkS")
		)
		(fp_line
			(start -1.3208 -0.7112)
			(end 1.3208 -0.7112)
			(stroke
				(width 0.1)
				(type default)
			)
			(layer "F.SilkS")
		)
		(fp_line
			(start 1.3208 0.7112)
			(end -1.3208 0.7112)
			(stroke
				(width 0.1)
				(type default)
			)
			(layer "F.SilkS")
		)
		(fp_line
			(start -1.3208 0.7112)
			(end -1.3208 -0.7112)
			(stroke
				(width 0.1)
				(type default)
			)
			(layer "F.SilkS")
		)
		(fp_rect
			(start -1.3208 0.7112)
			(end 1.3208 -0.7112)
			(stroke
				(width 0)
				(type default)
			)
			(fill no)
			(layer "F.CrtYd")
		)
		(fp_line
			(start 0.8128 -0.4572)
			(end 0.8128 0.4572)
			(stroke
				(width 0.1)
				(type default)
			)
			(layer "F.Fab")
		)
		(fp_line
			(start -0.8128 -0.4572)
			(end 0.8128 -0.4572)
			(stroke
				(width 0.1)
				(type default)
			)
			(layer "F.Fab")
		)
		(fp_line
			(start 0.8128 0.4572)
			(end -0.8128 0.4572)
			(stroke
				(width 0.1)
				(type default)
			)
			(layer "F.Fab")
		)
		(fp_line
			(start -0.8128 0.4572)
			(end -0.8128 -0.4572)
			(stroke
				(width 0.1)
				(type default)
			)
			(layer "F.Fab")
		)
		(pad "1" smd rect
			(at -0.6858 0 90)
			(size 0.762 0.8636)
			(layers "F.Cu" "F.Mask" "F.Paste")
			(net "XP5R0V")
		)
		(pad "2" smd rect
			(at 0.6858 0 90)
			(size 0.762 0.8636)
			(layers "F.Cu" "F.Mask" "F.Paste")
			(net "XP5R0V_VCC_ANT")
		)
		(zone
			(layer "F.Cu")
			(hatch none 0.5)
			(connect_pads
				(clearance 0)
			)
			(min_thickness 0.25)
			(keepout
				(tracks allowed)
				(vias not_allowed)
				(pads allowed)
				(copperpour not_allowed)
				(footprints allowed)
			)
			(placement
				(enabled no)
				(sheetname "")
			)
			(fill
				(thermal_gap 0.5)
				(thermal_bridge_width 0.5)
				(island_removal_mode 0)
			)
			(polygon
				(pts
					(xy 130.5052 -98.3996) (xy 130.5052 -98.7044) (xy 129.5908 -98.7044) (xy 129.5908 -98.3996)
				)
			)
		)
		(zone
			(layer "F.Cu")
			(hatch none 0.5)
			(connect_pads
				(clearance 0)
			)
			(min_thickness 0.25)
			(keepout
				(tracks not_allowed)
				(vias allowed)
				(pads allowed)
				(copperpour not_allowed)
				(footprints allowed)
			)
			(placement
				(enabled no)
				(sheetname "")
			)
			(fill
				(thermal_gap 0.5)
				(thermal_bridge_width 0.5)
				(island_removal_mode 0)
			)
			(polygon
				(pts
					(xy 130.5052 -98.3996) (xy 130.5052 -98.7044) (xy 129.5908 -98.7044) (xy 129.5908 -98.3996)
				)
			)
		)
	)
	(footprint ""
		(layer "F.Cu")
		(at 24.003 -75.946)
		(property "Reference" "TP9"
			(at 0 0 0)
			(layer "F.SilkS")
			(hide yes)
			(effects
				(font
					(size 1.27 1.27)
				)
			)
		)
		(property "Value" ""
			(at 0 0 0)
			(layer "F.Fab")
			(effects
				(font
					(size 1.27 1.27)
				)
			)
		)
		(property "Device Type" "TP_PIONT-TP010CT020B030_PTH-TPA"
			(at -1.341882 0.996696 0)
			(unlocked yes)
			(layer "F.Fab")
			(hide yes)
			(effects
				(font
					(size 0.7874 0.5842)
					(thickness 0.1524)
				)
				(justify left)
			)
		)
		(duplicate_pad_numbers_are_jumpers no)
		(fp_poly
			(pts
				(arc
					(start 0.889 0)
					(mid -0.889 0)
					(end 0.889 0)
				)
			)
			(stroke
				(width 0)
				(type default)
			)
			(fill no)
			(layer "B.CrtYd")
		)
		(fp_poly
			(pts
				(arc
					(start 0.889 0)
					(mid -0.889 0)
					(end 0.889 0)
				)
			)
			(stroke
				(width 0)
				(type default)
			)
			(fill no)
			(layer "F.CrtYd")
		)
		(pad "1" thru_hole circle
			(at 0 0)
			(size 0.508 0.508)
			(drill 0.254)
			(layers "*.Cu" "*.Mask")
			(remove_unused_layers no)
			(net "UNNAMED_524_FT4232HLREELQFP64_4")
			(clearance 0.1016)
			(padstack
				(mode front_inner_back)
				(layer "Inner"
					(shape circle)
					(size 0.508 0.508)
					(clearance 0.1016)
				)
				(layer "B.Cu"
					(shape circle)
					(size 0.762 0.762)
					(clearance -0.0254)
				)
			)
		)
	)
)
